# S9S_MB_2U (Grand Teton) — schematic netlist excerpt (pin names and nets, part order shuffled) for the footprints in the layout excerpt that follows; sources: Cadence DE-HDL packaged netlist, KiCad conversion of 03242023_DA0F0TMBIJ0_F0T_Motherboard_J_brd_V01_OCP.brd

C411  Q_CAP  22UF 4V 20% X6S  pkg C0402  page 74 : A = PVCCFA_EHV_FIVRA_CPU0 ; B = GND
PC2346  Q_CAPP  270UF 16V 20% OSCON  pkg THLF  page 285 : A = SW_P12V_PVCCIN_CPU1_FLT ; B = GND
R3660  Q_RES  10K 1% CHIP  pkg 0402LF  page 152 : A = P3V3_AUX ; B = RST_USB_HUB_R_N

(kicad_pcb
	(version 20260206)
	(generator "pcbnew")
	(generator_version "10.0")
	(general
		(thickness 1.6)
		(legacy_teardrops no)
	)
	(paper "A4")
	(title_block
		(title "03242023_DA0F0TMBIJ0_F0T_Motherboard_J_brd_V01_OCP.brd")
		(comment 1 "Grand Teton / footprints 3987-3989 of 6105")
	)
	(layers
		(0 "F.Cu" signal "TOP")
		(4 "In1.Cu" signal "GND")
		(6 "In2.Cu" signal "IN1")
		(8 "In3.Cu" signal "GND1")
		(10 "In4.Cu" signal "IN2")
		(12 "In5.Cu" signal "GND2")
		(14 "In6.Cu" signal "IN3")
		(16 "In7.Cu" signal "GND3")
		(18 "In8.Cu" signal "VCC")
		(20 "In9.Cu" signal "VCC1")
		(22 "In10.Cu" signal "GND4")
		(24 "In11.Cu" signal "IN4")
		(26 "In12.Cu" signal "GND5")
		(28 "In13.Cu" signal "IN5")
		(30 "In14.Cu" signal "GND6")
		(32 "In15.Cu" signal "IN6")
		(34 "In16.Cu" signal "GND7")
		(2 "B.Cu" signal "BOTTOM")
		(9 "F.Adhes" user "F.Adhesive")
		(11 "B.Adhes" user "B.Adhesive")
		(13 "F.Paste" user "Package Geometry/Pastemask Top")
		(15 "B.Paste" user "Package Geometry/Pastemask Bottom")
		(5 "F.SilkS" user "Ref Des/Silkscreen Top")
		(7 "B.SilkS" user "Ref Des/Silkscreen Bottom")
		(1 "F.Mask" user "Board Geometry/Soldermask Top")
		(3 "B.Mask" user "Board Geometry/Soldermask Bottom")
		(17 "Dwgs.User" user "User.Drawings")
		(19 "Cmts.User" user "User.Comments")
		(21 "Eco1.User" user "User.Eco1")
		(23 "Eco2.User" user "User.Eco2")
		(25 "Edge.Cuts" user "Board Geometry/Outline")
		(27 "Margin" user)
		(31 "F.CrtYd" user "Package Geometry/Place Bound Top")
		(29 "B.CrtYd" user "Package Geometry/Place Bound Bottom")
		(35 "F.Fab" user "Ref Des/Assembly Top")
		(33 "B.Fab" user "Ref Des/Assembly Bottom")
	)
	(footprint ""
		(layer "F.Cu")
		(at 365.46663 -260.364986 -90)
		(property "Reference" "C411"
			(at 0 0 270)
			(layer "F.SilkS")
			(hide yes)
			(effects
				(font
					(size 1.27 1.27)
				)
			)
		)
		(property "Value" ""
			(at 0 0 270)
			(layer "F.Fab")
			(effects
				(font
					(size 1.27 1.27)
				)
			)
		)
		(duplicate_pad_numbers_are_jumpers no)
		(fp_line
			(start -0.7874 0.4064)
			(end -0.7874 -0.4064)
			(stroke
				(width 0.1524)
				(type default)
			)
			(layer "F.SilkS")
		)
		(fp_line
			(start 0.7874 0.4064)
			(end -0.7874 0.4064)
			(stroke
				(width 0.1524)
				(type default)
			)
			(layer "F.SilkS")
		)
		(fp_line
			(start -0.7874 -0.4064)
			(end 0.7874 -0.4064)
			(stroke
				(width 0.1524)
				(type default)
			)
			(layer "F.SilkS")
		)
		(fp_line
			(start 0.7874 -0.4064)
			(end 0.7874 0.4064)
			(stroke
				(width 0.1524)
				(type default)
			)
			(layer "F.SilkS")
		)
		(fp_line
			(start -0.67945 0.3048)
			(end -0.67945 -0.305054)
			(stroke
				(width 0.1)
				(type default)
			)
			(layer "F.Fab")
		)
		(fp_line
			(start -0.12065 0.3048)
			(end -0.67945 0.3048)
			(stroke
				(width 0.1)
				(type default)
			)
			(layer "F.Fab")
		)
		(fp_line
			(start 0.120396 0.3048)
			(end 0.120396 0.2794)
			(stroke
				(width 0.1)
				(type default)
			)
			(layer "F.Fab")
		)
		(fp_line
			(start 0.67945 0.3048)
			(end 0.120396 0.3048)
			(stroke
				(width 0.1)
				(type default)
			)
			(layer "F.Fab")
		)
		(fp_line
			(start -0.12065 0.2794)
			(end -0.12065 0.3048)
			(stroke
				(width 0.1)
				(type default)
			)
			(layer "F.Fab")
		)
		(fp_line
			(start 0.120396 0.2794)
			(end -0.12065 0.2794)
			(stroke
				(width 0.1)
				(type default)
			)
			(layer "F.Fab")
		)
		(fp_line
			(start -0.12065 -0.2794)
			(end 0.12065 -0.2794)
			(stroke
				(width 0.1)
				(type default)
			)
			(layer "F.Fab")
		)
		(fp_line
			(start 0.12065 -0.2794)
			(end 0.12065 -0.3048)
			(stroke
				(width 0.1)
				(type default)
			)
			(layer "F.Fab")
		)
		(fp_line
			(start 0.12065 -0.3048)
			(end 0.67945 -0.3048)
			(stroke
				(width 0.1)
				(type default)
			)
			(layer "F.Fab")
		)
		(fp_line
			(start 0.67945 -0.3048)
			(end 0.67945 0.3048)
			(stroke
				(width 0.1)
				(type default)
			)
			(layer "F.Fab")
		)
		(fp_line
			(start -0.67945 -0.305054)
			(end -0.12065 -0.305054)
			(stroke
				(width 0.1)
				(type default)
			)
			(layer "F.Fab")
		)
		(fp_line
			(start -0.12065 -0.305054)
			(end -0.12065 -0.2794)
			(stroke
				(width 0.1)
				(type default)
			)
			(layer "F.Fab")
		)
		(pad "1" smd circle
			(at -0.40005 0 270)
			(size 0 0)
			(layers "F.Cu" "F.Mask" "F.Paste")
			(net "PVCCFA_EHV_FIVRA_CPU0")
		)
		(pad "2" smd circle
			(at 0.40005 0 270)
			(size 0 0)
			(layers "F.Cu" "F.Mask" "F.Paste")
			(net "GND")
		)
	)
	(footprint ""
		(layer "F.Cu")
		(at 12.982956 -92.687648 90)
		(property "Reference" "R3660"
			(at 0 0 90)
			(layer "F.SilkS")
			(hide yes)
			(effects
				(font
					(size 1.27 1.27)
				)
			)
		)
		(property "Value" ""
			(at 0 0 90)
			(layer "F.Fab")
			(effects
				(font
					(size 1.27 1.27)
				)
			)
		)
		(duplicate_pad_numbers_are_jumpers no)
		(fp_line
			(start 0.7874 -0.4064)
			(end 0.7874 0.4064)
			(stroke
				(width 0.1524)
				(type default)
			)
			(layer "F.SilkS")
		)
		(fp_line
			(start -0.7874 -0.4064)
			(end 0.7874 -0.4064)
			(stroke
				(width 0.1524)
				(type default)
			)
			(layer "F.SilkS")
		)
		(fp_line
			(start 0.7874 0.4064)
			(end -0.7874 0.4064)
			(stroke
				(width 0.1524)
				(type default)
			)
			(layer "F.SilkS")
		)
		(fp_line
			(start -0.7874 0.4064)
			(end -0.7874 -0.4064)
			(stroke
				(width 0.1524)
				(type default)
			)
			(layer "F.SilkS")
		)
		(fp_line
			(start -0.12065 -0.305054)
			(end -0.12065 -0.2794)
			(stroke
				(width 0.1)
				(type default)
			)
			(layer "F.Fab")
		)
		(fp_line
			(start -0.67945 -0.305054)
			(end -0.12065 -0.305054)
			(stroke
				(width 0.1)
				(type default)
			)
			(layer "F.Fab")
		)
		(fp_line
			(start 0.67945 -0.3048)
			(end 0.67945 0.3048)
			(stroke
				(width 0.1)
				(type default)
			)
			(layer "F.Fab")
		)
		(fp_line
			(start 0.12065 -0.3048)
			(end 0.67945 -0.3048)
			(stroke
				(width 0.1)
				(type default)
			)
			(layer "F.Fab")
		)
		(fp_line
			(start 0.12065 -0.2794)
			(end 0.12065 -0.3048)
			(stroke
				(width 0.1)
				(type default)
			)
			(layer "F.Fab")
		)
		(fp_line
			(start -0.12065 -0.2794)
			(end 0.12065 -0.2794)
			(stroke
				(width 0.1)
				(type default)
			)
			(layer "F.Fab")
		)
		(fp_line
			(start 0.120396 0.2794)
			(end -0.12065 0.2794)
			(stroke
				(width 0.1)
				(type default)
			)
			(layer "F.Fab")
		)
		(fp_line
			(start -0.12065 0.2794)
			(end -0.12065 0.3048)
			(stroke
				(width 0.1)
				(type default)
			)
			(layer "F.Fab")
		)
		(fp_line
			(start 0.67945 0.3048)
			(end 0.120396 0.3048)
			(stroke
				(width 0.1)
				(type default)
			)
			(layer "F.Fab")
		)
		(fp_line
			(start 0.120396 0.3048)
			(end 0.120396 0.2794)
			(stroke
				(width 0.1)
				(type default)
			)
			(layer "F.Fab")
		)
		(fp_line
			(start -0.12065 0.3048)
			(end -0.67945 0.3048)
			(stroke
				(width 0.1)
				(type default)
			)
			(layer "F.Fab")
		)
		(fp_line
			(start -0.67945 0.3048)
			(end -0.67945 -0.305054)
			(stroke
				(width 0.1)
				(type default)
			)
			(layer "F.Fab")
		)
		(pad "1" smd circle
			(at -0.40005 0 90)
			(size 0 0)
			(layers "F.Cu" "F.Mask" "F.Paste")
			(net "P3V3_AUX")
		)
		(pad "2" smd circle
			(at 0.40005 0 90)
			(size 0 0)
			(layers "F.Cu" "F.Mask" "F.Paste")
			(net "RST_USB_HUB_R_N")
		)
	)
	(footprint ""
		(layer "F.Cu")
		(at 116.4844 -350.434148 90)
		(property "Reference" "PC2346"
			(at 0 0 90)
			(layer "F.SilkS")
			(hide yes)
			(effects
				(font
					(size 1.27 1.27)
				)
			)
		)
		(property "Value" ""
			(at 0 0 90)
			(layer "F.Fab")
			(effects
				(font
					(size 1.27 1.27)
				)
			)
		)
		(duplicate_pad_numbers_are_jumpers no)
		(fp_line
			(start -3.400044 1.249934)
			(end 3.400044 1.249934)
			(stroke
				(width 0.1524)
				(type default)
			)
			(layer "F.SilkS")
		)
		(fp_circle
			(center 0 1.249934)
			(end 0 4.649978)
			(stroke
				(width 0.1524)
				(type default)
			)
			(fill no)
			(layer "F.SilkS")
		)
		(fp_poly
			(pts
				(arc
					(start -3.400044 1.249934)
					(mid 0 4.649978)
					(end 3.400044 1.249934)
				)
			)
			(stroke
				(width 0)
				(type default)
			)
			(fill yes)
			(layer "F.SilkS")
		)
		(fp_circle
			(center 0 1.249934)
			(end 0 4.649978)
			(stroke
				(width 0.1)
				(type default)
			)
			(fill no)
			(layer "F.Fab")
		)
		(pad "1" thru_hole rect
			(at 0 0 90)
			(size 1.524 1.524)
			(drill 1.016)
			(layers "*.Cu" "*.Mask")
			(remove_unused_layers no)
			(net "SW_P12V_PVCCIN_CPU1_FLT")
			(clearance 0)
			(padstack
				(mode front_inner_back)
				(layer "Inner"
					(shape circle)
					(size 1.524 1.524)
					(clearance 0)
				)
				(layer "B.Cu"
					(shape rect)
					(size 1.524 1.524)
					(clearance 0)
				)
			)
		)
		(pad "2" thru_hole circle
			(at 0 2.500122 90)
			(size 1.524 1.524)
			(drill 1.016)
			(layers "*.Cu" "*.Mask")
			(remove_unused_layers no)
			(net "GND")
			(clearance 0)
		)
	)
)
